# TIMECARD (Time Appliance Project (Time Card)) — schematic netlist excerpt (pin names and nets, part order shuffled) for the footprints in the layout excerpt that follows; sources: Cadence DE-HDL packaged netlist, KiCad conversion of R4006-B0001-02_R01.brd

R162  RESISTOR  4.7KOHM 1%  pkg SMC_0402R_H016  page 16 : \1\ = XP3R3V_FPGA ; \2\ = UNNAMED_5_24LC16BTISTTSSOP8_I_2
R267  RESISTOR  33OHM 1%  pkg SMC_0402R_H016  page 21 : \1\ = UNNAMED_527_RESISTOR_I206_1 ; \2\ = FPGA_IN_MAC_USB_OC_N

(kicad_pcb
	(version 20260206)
	(generator "pcbnew")
	(generator_version "10.0")
	(general
		(thickness 1.6)
		(legacy_teardrops no)
	)
	(paper "A4")
	(title_block
		(title "timecard-production-celestica-r4006 — R4006-B0001-02_R01.brd")
		(comment 1 "Time Appliance Project (Time Card) / footprints 915-916 of 1113")
	)
	(layers
		(0 "F.Cu" signal "TOP")
		(4 "In1.Cu" signal "L02_GND1")
		(6 "In2.Cu" signal "L03_SIG1")
		(8 "In3.Cu" signal "L04_GND2")
		(10 "In4.Cu" signal "L05_VCC1")
		(12 "In5.Cu" signal "L06_VCC2")
		(14 "In6.Cu" signal "L07_GND3")
		(16 "In7.Cu" signal "L08_SIG2")
		(18 "In8.Cu" signal "L09_GND4")
		(2 "B.Cu" signal "BOTTOM")
		(9 "F.Adhes" user "F.Adhesive")
		(11 "B.Adhes" user "B.Adhesive")
		(13 "F.Paste" user "Package Geometry/Pastemask Top")
		(15 "B.Paste" user "Package Geometry/Pastemask Bottom")
		(5 "F.SilkS" user "Ref Des/Silkscreen Top")
		(7 "B.SilkS" user "Ref Des/Silkscreen Bottom")
		(1 "F.Mask" user "Board Geometry/Soldermask Top")
		(3 "B.Mask" user "Board Geometry/Soldermask Bottom")
		(17 "Dwgs.User" user "User.Drawings")
		(19 "Cmts.User" user "User.Comments")
		(21 "Eco1.User" user "User.Eco1")
		(23 "Eco2.User" user "User.Eco2")
		(25 "Edge.Cuts" user "Board Geometry/Outline")
		(27 "Margin" user)
		(31 "F.CrtYd" user "Package Geometry/Place Bound Top")
		(29 "B.CrtYd" user "Package Geometry/Place Bound Bottom")
		(35 "F.Fab" user "Ref Des/Assembly Top")
		(33 "B.Fab" user "Ref Des/Assembly Bottom")
	)
	(footprint ""
		(layer "B.Cu")
		(at 66.548 -60.325)
		(property "Reference" "R267"
			(at -1.143 -1.10363 0)
			(unlocked yes)
			(layer "B.SilkS")
			(effects
				(font
					(size 0.7874 0.5842)
					(thickness 0.1524)
				)
				(justify mirror)
			)
		)
		(property "Value" "VAL*"
			(at -0.02032 2.13233 0)
			(unlocked yes)
			(layer "B.Fab")
			(hide yes)
			(effects
				(font
					(size 0.7874 0.5842)
					(thickness 0.1524)
				)
				(justify mirror)
			)
		)
		(property "Device Type" "RESISTOR-G155-133R0-01,33OHM,1%"
			(at -0.008382 1.210564 0)
			(unlocked yes)
			(layer "B.Fab")
			(hide yes)
			(effects
				(font
					(size 0.7874 0.5842)
					(thickness 0.1524)
				)
				(justify mirror)
			)
		)
		(property "User Part Number" "PARTNUM*"
			(at -0.02032 4.024884 0)
			(unlocked yes)
			(layer "Cmts.User")
			(hide yes)
			(effects
				(font
					(size 0.7874 0.5842)
					(thickness 0.1524)
				)
				(justify mirror)
			)
		)
		(property "Tolerance" "TOL*"
			(at -0.044704 3.05435 0)
			(unlocked yes)
			(layer "Cmts.User")
			(hide yes)
			(effects
				(font
					(size 0.7874 0.5842)
					(thickness 0.1524)
				)
				(justify mirror)
			)
		)
		(duplicate_pad_numbers_are_jumpers no)
		(fp_line
			(start -1.143 -0.5588)
			(end 1.143 -0.5588)
			(stroke
				(width 0.1)
				(type default)
			)
			(layer "B.SilkS")
		)
		(fp_line
			(start -1.143 0.5588)
			(end -1.143 -0.5588)
			(stroke
				(width 0.1)
				(type default)
			)
			(layer "B.SilkS")
		)
		(fp_line
			(start 1.143 -0.5588)
			(end 1.143 0.5588)
			(stroke
				(width 0.1)
				(type default)
			)
			(layer "B.SilkS")
		)
		(fp_line
			(start 1.143 0.5588)
			(end -1.143 0.5588)
			(stroke
				(width 0.1)
				(type default)
			)
			(layer "B.SilkS")
		)
		(fp_rect
			(start -1.143 0.5588)
			(end 1.143 -0.5588)
			(stroke
				(width 0)
				(type default)
			)
			(fill no)
			(layer "B.CrtYd")
		)
		(fp_line
			(start -0.508 -0.3048)
			(end 0.508 -0.3048)
			(stroke
				(width 0.1)
				(type default)
			)
			(layer "B.Fab")
		)
		(fp_line
			(start -0.508 0.3048)
			(end -0.508 -0.3048)
			(stroke
				(width 0.1)
				(type default)
			)
			(layer "B.Fab")
		)
		(fp_line
			(start 0.508 -0.3048)
			(end 0.508 0.3048)
			(stroke
				(width 0.1)
				(type default)
			)
			(layer "B.Fab")
		)
		(fp_line
			(start 0.508 0.3048)
			(end -0.508 0.3048)
			(stroke
				(width 0.1)
				(type default)
			)
			(layer "B.Fab")
		)
		(pad "1" smd rect
			(at 0.5334 0 180)
			(size 0.7112 0.6096)
			(layers "B.Cu" "B.Mask" "B.Paste")
			(net "UNNAMED_527_RESISTOR_I206_1")
		)
		(pad "2" smd rect
			(at -0.5334 0 180)
			(size 0.7112 0.6096)
			(layers "B.Cu" "B.Mask" "B.Paste")
			(net "FPGA_IN_MAC_USB_OC_N")
		)
		(zone
			(layer "B.Cu")
			(hatch none 0.5)
			(connect_pads
				(clearance 0)
			)
			(min_thickness 0.25)
			(keepout
				(tracks allowed)
				(vias not_allowed)
				(pads allowed)
				(copperpour not_allowed)
				(footprints allowed)
			)
			(placement
				(enabled no)
				(sheetname "")
			)
			(fill
				(thermal_gap 0.5)
				(thermal_bridge_width 0.5)
				(island_removal_mode 0)
			)
			(polygon
				(pts
					(xy 66.4718 -60.0202) (xy 66.6242 -60.0202) (xy 66.6242 -60.6298) (xy 66.4718 -60.6298)
				)
			)
		)
	)
	(footprint ""
		(layer "B.Cu")
		(at 18.8722 -23.6728 -90)
		(property "Reference" "R162"
			(at -3.2512 1.00457 270)
			(unlocked yes)
			(layer "B.SilkS")
			(effects
				(font
					(size 0.7874 0.5842)
					(thickness 0.1524)
				)
				(justify mirror)
			)
		)
		(property "Value" "VAL*"
			(at -0.02032 2.13233 270)
			(unlocked yes)
			(layer "B.Fab")
			(hide yes)
			(effects
				(font
					(size 0.7874 0.5842)
					(thickness 0.1524)
				)
				(justify mirror)
			)
		)
		(property "Tolerance" "TOL*"
			(at -0.044704 3.05435 270)
			(unlocked yes)
			(layer "Cmts.User")
			(hide yes)
			(effects
				(font
					(size 0.7874 0.5842)
					(thickness 0.1524)
				)
				(justify mirror)
			)
		)
		(property "User Part Number" "PARTNUM*"
			(at -0.02032 4.024884 270)
			(unlocked yes)
			(layer "Cmts.User")
			(hide yes)
			(effects
				(font
					(size 0.7874 0.5842)
					(thickness 0.1524)
				)
				(justify mirror)
			)
		)
		(property "Device Type" "RESISTOR-G155-14701-01,4.7KOHMA"
			(at -0.008382 1.210564 270)
			(unlocked yes)
			(layer "B.Fab")
			(hide yes)
			(effects
				(font
					(size 0.7874 0.5842)
					(thickness 0.1524)
				)
				(justify mirror)
			)
		)
		(duplicate_pad_numbers_are_jumpers no)
		(fp_line
			(start -1.143 0.5588)
			(end -1.143 -0.5588)
			(stroke
				(width 0.1)
				(type default)
			)
			(layer "B.SilkS")
		)
		(fp_line
			(start 1.143 0.5588)
			(end -1.143 0.5588)
			(stroke
				(width 0.1)
				(type default)
			)
			(layer "B.SilkS")
		)
		(fp_line
			(start -1.143 -0.5588)
			(end 1.143 -0.5588)
			(stroke
				(width 0.1)
				(type default)
			)
			(layer "B.SilkS")
		)
		(fp_line
			(start 1.143 -0.5588)
			(end 1.143 0.5588)
			(stroke
				(width 0.1)
				(type default)
			)
			(layer "B.SilkS")
		)
		(fp_rect
			(start -1.143 0.5588)
			(end 1.143 -0.5588)
			(stroke
				(width 0)
				(type default)
			)
			(fill no)
			(layer "B.CrtYd")
		)
		(fp_line
			(start -0.508 0.3048)
			(end -0.508 -0.3048)
			(stroke
				(width 0.1)
				(type default)
			)
			(layer "B.Fab")
		)
		(fp_line
			(start 0.508 0.3048)
			(end -0.508 0.3048)
			(stroke
				(width 0.1)
				(type default)
			)
			(layer "B.Fab")
		)
		(fp_line
			(start -0.508 -0.3048)
			(end 0.508 -0.3048)
			(stroke
				(width 0.1)
				(type default)
			)
			(layer "B.Fab")
		)
		(fp_line
			(start 0.508 -0.3048)
			(end 0.508 0.3048)
			(stroke
				(width 0.1)
				(type default)
			)
			(layer "B.Fab")
		)
		(pad "1" smd rect
			(at 0.5334 0 90)
			(size 0.7112 0.6096)
			(layers "B.Cu" "B.Mask" "B.Paste")
			(net "XP3R3V_FPGA")
		)
		(pad "2" smd rect
			(at -0.5334 0 90)
			(size 0.7112 0.6096)
			(layers "B.Cu" "B.Mask" "B.Paste")
			(net "UNNAMED_5_24LC16BTISTTSSOP8_I_2")
		)
		(zone
			(layer "B.Cu")
			(hatch none 0.5)
			(connect_pads
				(clearance 0)
			)
			(min_thickness 0.25)
			(keepout
				(tracks allowed)
				(vias not_allowed)
				(pads allowed)
				(copperpour not_allowed)
				(footprints allowed)
			)
			(placement
				(enabled no)
				(sheetname "")
			)
			(fill
				(thermal_gap 0.5)
				(thermal_bridge_width 0.5)
				(island_removal_mode 0)
			)
			(polygon
				(pts
					(xy 18.5674 -23.749) (xy 18.5674 -23.5966) (xy 19.177 -23.5966) (xy 19.177 -23.749)
				)
			)
		)
	)
)
